#ISCELL
  mstr_misc dns *
  *
#ISCELL
  pure_quanta quanta_title_block_c *
  *
#ISCELL
  standard offpage *
  page186_i1
#ISCELL
  pure_quanta_power universal_gnd *
  page186_i10
#CELL
  pure_quanta q_res *
  page186_i11
#ISCELL
  pure_quanta_power universal_gnd *
  page186_i12
#CELL
  pure_quanta q_cap *
  page186_i13
#ISCELL
  pure_quanta_power vcc_core *
  page186_i14
#ISCELL
  pure_quanta_power universal_gnd *
  page186_i15
#CELL
  pure_quanta q_cap *
  page186_i16
#ISCELL
  pure_quanta_power universal_gnd *
  page186_i17
#ISCELL
  standard offpage *
  page186_i18
#ISCELL
  standard offpage *
  page186_i19
#ISCELL
  standard offpage *
  page186_i2
#ISCELL
  pure_quanta_power universal_gnd *
  page186_i20
#ISCELL
  pure_quanta_power universal_gnd *
  page186_i21
#CELL
  pure_quanta q_res *
  page186_i22
#CELL
  pure_quanta q_res *
  page186_i23
#CELL
  pure_quanta q_cap *
  page186_i24
#CELL
  pure_quanta q_cap *
  page186_i25
#CELL
  pure_quanta q_cap *
  page186_i26
#ISCELL
  pure_quanta_power universal_gnd *
  page186_i27
#CELL
  pure_quanta q_cap *
  page186_i28
#CELL
  pure_quanta q_cap *
  page186_i29
#CELL
  pure_quanta q_res *
  page186_i3
#ISCELL
  pure_quanta_power universal_gnd *
  page186_i30
#CELL
  pure_quanta q_cap *
  page186_i31
#ISCELL
  pure_quanta_power vcc_core *
  page186_i32
#ISCELL
  pure_quanta_power universal_gnd *
  page186_i33
#CELL
  pure_quanta q_res *
  page186_i34
#CELL
  pure_quanta q_res *
  page186_i35
#CELL
  pure_quanta q_cap *
  page186_i36
#CELL
  pure_quanta q_res *
  page186_i37
#ISCELL
  standard offpage *
  page186_i38
#ISCELL
  pure_quanta_power universal_gnd *
  page186_i39
#ISCELL
  pure_quanta_power vcc_core *
  page186_i4
#ISCELL
  pure_quanta_power universal_gnd *
  page186_i40
#CELL
  pure_quanta q_res *
  page186_i41
#ISCELL
  pure_quanta_power vcc_core *
  page186_i42
#CELL
  pure_quanta q_res *
  page186_i43
#CELL
  pure_quanta q_cap *
  page186_i44
#ISCELL
  pure_quanta_power vcc_core *
  page186_i45
#CELL
  pure_quanta q_cap *
  page186_i46
#CELL
  pure_quanta q_cap *
  page186_i47
#CELL
  pure_quanta q_cap *
  page186_i48
#CELL
  pure_quanta q_res *
  page186_i49
#CELL
  pure_quanta q_cap *
  page186_i5
#ISCELL
  standard offpage *
  page186_i50
#CELL
  pure_quanta q_cap *
  page186_i51
#CELL
  pure_quanta q_cap *
  page186_i52
#CELL
  pure_quanta q_cap *
  page186_i53
#ISCELL
  standard offpage *
  page186_i54
#CELL
  pure_quanta q_cap *
  page186_i55
#CELL
  pure_quanta q_inductor4p_14 *
  page186_i56
#ISCELL
  standard offpage *
  page186_i57
#CELL
  pure_quanta q_capp *
  page186_i58
#CELL
  pure_quanta q_capp *
  page186_i59
#ISCELL
  standard offpage *
  page186_i6
#CELL
  pure_quanta q_capp *
  page186_i60
#CELL
  pure_quanta q_cap *
  page186_i61
#ISCELL
  pure_quanta_power universal_gnd *
  page186_i62
#CELL
  pure_quanta q_cap *
  page186_i63
#ISCELL
  pure_quanta_power vcc_core *
  page186_i64
#ISCELL
  pure_quanta_power universal_gnd *
  page186_i65
#CELL
  pure_quanta q_capp *
  page186_i66
#ISCELL
  pure_quanta_power vcc_core *
  page186_i67
#ISCELL
  pure_quanta_power universal_gnd *
  page186_i68
#ISCELL
  pure_quanta_power universal_gnd *
  page186_i69
#ISCELL
  standard offpage *
  page186_i7
#CELL
  pure_quanta q_capp *
  page186_i70
#CELL
  pure_quanta q_capp *
  page186_i71
#ISCELL
  standard offpage *
  page186_i72
#CELL
  pure_quanta q_inductor *
  page186_i73
#CELL
  pure_quanta q_cap *
  page186_i74
#ISCELL
  pure_quanta_power vcc_core *
  page186_i75
#CELL
  pure_quanta q_cap *
  page186_i76
#CELL
  pure_quanta q_cap *
  page186_i77
#CELL
  pure_quanta q_res *
  page186_i78
#ISCELL
  pure_quanta_power vcc_core *
  page186_i79
#ISCELL
  standard offpage *
  page186_i8
#CELL
  pure_quanta q_res *
  page186_i80
#ISCELL
  pure_quanta_power universal_gnd *
  page186_i81
#ISCELL
  pure_quanta_power universal_gnd *
  page186_i82
#CELL
  pure_quanta q_res *
  page186_i83
#CELL
  pure_quanta q_capp *
  page186_i84
#CELL
  pure_quanta q_cap *
  page186_i85
#ISCELL
  pure_quanta_power universal_gnd *
  page186_i86
#ISCELL
  pure_quanta_power vcc_core *
  page186_i87
#CELL
  pure_quanta isl99390frztr5935 *
  page186_i88
#CELL
  pure_quanta q_cap *
  page186_i89
#CELL
  pure_quanta q_cap *
  page186_i9
#CELL
  pure_quanta q_inductor4p_14 *
  page186_i90
#CELL
  pure_quanta isl99390frztr5935 *
  page186_i91
